FILE_TYPE=LIBRARY_PARTS;
primitive 'TTL2G14';
  pin
    'A'<0>:
      PIN_NUMBER='(1,3)';
      INPUT_LOAD='(-0.01,0.01)';
    'Y'<0>:
      PIN_NUMBER='(6,4)';
      OUTPUT_LOAD='(1.00,-1.00)';
  end_pin;
  body
    POWER_PINS='(VCC:5)';
    POWER_PINS='(GND:2)';
    PART_NAME='TTL2G14';
    PHYS_DES_PREFIX='U';
  end_body;
end_primitive;
END.
